FILE_TYPE = CONNECTIVITY;
{Allegro Design Entry HDL 16.6-p007 (v16-6-112F) 10/10/2012}
"PAGE_NUMBER" = 15;
0"NC";
END.
